# BASEBOARD_FAB2 (Tioga Pass) — schematic parts with pin connectivity, parts 2374–2374 of 4751; source: Cadence DE-HDL packaged netlist (pstxprt.dat, pstxnet.dat, pstchip.dat)

J6L2  SCONN288_H44441003  SCONN  pkg PIP  page 52
  1  \12v\(1)  = P12V_NVDIMM_DEF
  2  VSS(93)  GROUND  = GND
  3  DQ(4)  BI  = M_E_DQ<4>
  4  VSS(92)  GROUND  = GND
  5  DQ(0)  BI  = M_E_DQ<0>
  6  VSS(91)  GROUND  = GND
  7  DQS9P  BI  = M_E_DQS_DP<9>
  8  DQS9N  BI  = M_E_DQS_DN<9>
  9  VSS(90)  GROUND  = GND
  10  DQ(6)  BI  = M_E_DQ<6>
  11  VSS(89)  GROUND  = GND
  12  DQ(2)  BI  = M_E_DQ<2>
  13  VSS(88)  GROUND  = GND
  14  DQ(12)  BI  = M_E_DQ<12>
  15  VSS(87)  GROUND  = GND
  16  DQ(8)  BI  = M_E_DQ<8>
  17  VSS(86)  GROUND  = GND
  18  DQS10P  BI  = M_E_DQS_DP<10>
  19  DQS10N  BI  = M_E_DQS_DN<10>
  20  VSS(85)  GROUND  = GND
  21  DQ(14)  BI  = M_E_DQ<14>
  22  VSS(84)  GROUND  = GND
  23  DQ(10)  BI  = M_E_DQ<10>
  24  VSS(83)  GROUND  = GND
  25  DQ(20)  BI  = M_E_DQ<20>
  26  VSS(82)  GROUND  = GND
  27  DQ(16)  BI  = M_E_DQ<16>
  28  VSS(81)  GROUND  = GND
  29  DQS11P  BI  = M_E_DQS_DP<11>
  30  DQS11N  BI  = M_E_DQS_DN<11>
  31  VSS(80)  GROUND  = GND
  32  DQ(22)  BI  = M_E_DQ<22>
  33  VSS(79)  GROUND  = GND
  34  DQ(18)  BI  = M_E_DQ<18>
  35  VSS(78)  GROUND  = GND
  36  DQ(28)  BI  = M_E_DQ<28>
  37  VSS(77)  GROUND  = GND
  38  DQ(24)  BI  = M_E_DQ<24>
  39  VSS(76)  GROUND  = GND
  40  DQS12P  BI  = M_E_DQS_DP<12>
  41  DQS12N  BI  = M_E_DQS_DN<12>
  42  VSS(75)  GROUND  = GND
  43  DQ(30)  BI  = M_E_DQ<30>
  44  VSS(74)  GROUND  = GND
  45  DQ(26)  BI  = M_E_DQ<26>
  46  VSS(73)  GROUND  = GND
  47  CB(4)  BI  = M_E_ECC<4>
  48  VSS(72)  GROUND  = GND
  49  CB(0)  BI  = M_E_ECC<0>
  50  VSS(71)  GROUND  = GND
  51  DQS17P  BI  = M_E_DQS_DP<17>
  52  DQS17N  BI  = M_E_DQS_DN<17>
  53  VSS(70)  GROUND  = GND
  54  CB(6)  BI  = M_E_ECC<6>
  55  VSS(69)  GROUND  = GND
  56  CB(2)  BI  = M_E_ECC<2>
  57  VSS(68)  GROUND  = GND
  58  RESET_N  BI  = M_DEF_RST_N
  59  VDD(25)  POWER  = PVDDQ_DEF
  60  CKE(0)  BI  = M_E_CKE<2>
  61  VDD(24)  POWER  = PVDDQ_DEF
  62  ACT_N  BI  = M_E_ACT_N
  63  BG(0)  BI  = M_E_BG<0>
  64  VDD(23)  POWER  = PVDDQ_DEF
  65  A12  BI  = M_E_MA<12>
  66  A9  BI  = M_E_MA<9>
  67  VDD(22)  POWER  = PVDDQ_DEF
  68  A8  BI  = M_E_MA<8>
  69  A6  BI  = M_E_MA<6>
  70  VDD(21)  POWER  = PVDDQ_DEF
  71  A3  BI  = M_E_MA<3>
  72  A1  BI  = M_E_MA<1>
  73  VDD(20)  POWER  = PVDDQ_DEF
  74  CK0P  BI  = M_E_CLK_DP<2>
  75  CK0N  BI  = M_E_CLK_DN<2>
  76  VDD(19)  POWER  = PVDDQ_DEF
  77  VTT(1)  POWER  = PVTT_DEF
  78  EVENT_N  BI  = FM_DIMM_EVENT_COD_N
  79  A0  BI  = M_E_MA<0>
  80  VDD(18)  POWER  = PVDDQ_DEF
  81  BA(0)  BI  = M_E_BA<0>
  82  A16_RAS_N  BI  = M_E_MA<16>
  83  VDD(17)  POWER  = PVDDQ_DEF
  84  S0_N  BI  = M_E_CS_N<4>
  85  VDD(16)  POWER  = PVDDQ_DEF
  86  A15_CAS_N  BI  = M_E_MA<15>
  87  ODT(0)  BI  = M_E_ODT<2>
  88  VDD(15)  POWER  = PVDDQ_DEF
  89  S1_N  BI  = M_E_CS_N<5>
  90  VDD(14)  POWER  = PVDDQ_DEF
  91  ODT(1)  BI  = M_E_ODT<3>
  92  VDD(13)  POWER  = PVDDQ_DEF
  93  S2_N_C(0)  BI  = M_E_CS_N<6>
  94  VSS(67)  GROUND  = GND
  95  DQ(36)  BI  = M_E_DQ<36>
  96  VSS(66)  GROUND  = GND
  97  DQ(32)  BI  = M_E_DQ<32>
  98  VSS(65)  GROUND  = GND
  99  DQS13P  BI  = M_E_DQS_DP<13>
  100  DQS13N  BI  = M_E_DQS_DN<13>
  101  VSS(64)  GROUND  = GND
  102  DQ(38)  BI  = M_E_DQ<38>
  103  VSS(63)  GROUND  = GND
  104  DQ(34)  BI  = M_E_DQ<34>
  105  VSS(62)  GROUND  = GND
  106  DQ(44)  BI  = M_E_DQ<44>
  107  VSS(61)  GROUND  = GND
  108  DQ(40)  BI  = M_E_DQ<40>
  109  VSS(60)  GROUND  = GND
  110  DQS14P  BI  = M_E_DQS_DP<14>
  111  DQS14N  BI  = M_E_DQS_DN<14>
  112  VSS(59)  GROUND  = GND
  113  DQ(46)  BI  = M_E_DQ<46>
  114  VSS(58)  GROUND  = GND
  115  DQ(42)  BI  = M_E_DQ<42>
  116  VSS(57)  GROUND  = GND
  117  DQ(52)  BI  = M_E_DQ<52>
  118  VSS(56)  GROUND  = GND
  119  DQ(48)  BI  = M_E_DQ<48>
  120  VSS(55)  GROUND  = GND
  121  DQS15P  BI  = M_E_DQS_DP<15>
  122  DQS15N  BI  = M_E_DQS_DN<15>
  123  VSS(54)  GROUND  = GND
  124  DQ(54)  BI  = M_E_DQ<54>
  125  VSS(53)  GROUND  = GND
  126  DQ(50)  BI  = M_E_DQ<50>
  127  VSS(52)  GROUND  = GND
  128  DQ(60)  BI  = M_E_DQ<60>
  129  VSS(51)  GROUND  = GND
  130  DQ(56)  BI  = M_E_DQ<56>
  131  VSS(50)  GROUND  = GND
  132  DQS16P  BI  = M_E_DQS_DP<16>
  133  DQS16N  BI  = M_E_DQS_DN<16>
  134  VSS(49)  GROUND  = GND
  135  DQ(62)  BI  = M_E_DQ<62>
  136  VSS(48)  GROUND  = GND
  137  DQ(58)  BI  = M_E_DQ<58>
  138  VSS(47)  GROUND  = GND
  139  SA(0)  BI  = PVPP_DEF
  140  SA(1)  BI  = PVPP_DEF
  141  SCL  BI  = SMB_DDR_DEF_VPP_SCL
  142  VPP(4)  POWER  = PVPP_DEF
  143  VPP(3)  POWER  = PVPP_DEF
  144  RFU(2)  BI  = TP_CH_E_DIMM_E1_RFU_2
  145  \12v\(0)  = P12V_NVDIMM_DEF
  146  VREFCA  BI  = M_E_VREF
  147  VSS(46)  GROUND  = GND
  148  DQ(5)  BI  = M_E_DQ<5>
  149  VSS(45)  GROUND  = GND
  150  DQ(1)  BI  = M_E_DQ<1>
  151  VSS(44)  GROUND  = GND
  152  DQS0N  BI  = M_E_DQS_DN<0>
  153  DQS0P  BI  = M_E_DQS_DP<0>
  154  VSS(43)  GROUND  = GND
  155  DQ(7)  BI  = M_E_DQ<7>
  156  VSS(42)  GROUND  = GND
  157  DQ(3)  BI  = M_E_DQ<3>
  158  VSS(41)  GROUND  = GND
  159  DQ(13)  BI  = M_E_DQ<13>
  160  VSS(40)  GROUND  = GND
  161  DQ(9)  BI  = M_E_DQ<9>
  162  VSS(39)  GROUND  = GND
  163  DQS1N  BI  = M_E_DQS_DN<1>
  164  DQS1P  BI  = M_E_DQS_DP<1>
  165  VSS(38)  GROUND  = GND
  166  DQ(15)  BI  = M_E_DQ<15>
  167  VSS(37)  GROUND  = GND
  168  DQ(11)  BI  = M_E_DQ<11>
  169  VSS(36)  GROUND  = GND
  170  DQ(21)  BI  = M_E_DQ<21>
  171  VSS(35)  GROUND  = GND
  172  DQ(17)  BI  = M_E_DQ<17>
  173  VSS(34)  GROUND  = GND
  174  DQS2N  BI  = M_E_DQS_DN<2>
  175  DQS2P  BI  = M_E_DQS_DP<2>
  176  VSS(33)  GROUND  = GND
  177  DQ(23)  BI  = M_E_DQ<23>
  178  VSS(32)  GROUND  = GND
  179  DQ(19)  BI  = M_E_DQ<19>
  180  VSS(31)  GROUND  = GND
  181  DQ(29)  BI  = M_E_DQ<29>
  182  VSS(30)  GROUND  = GND
  183  DQ(25)  BI  = M_E_DQ<25>
  184  VSS(29)  GROUND  = GND
  185  DQS3N  BI  = M_E_DQS_DN<3>
  186  DQS3P  BI  = M_E_DQS_DP<3>
  187  VSS(28)  GROUND  = GND
  188  DQ(31)  BI  = M_E_DQ<31>
  189  VSS(27)  GROUND  = GND
  190  DQ(27)  BI  = M_E_DQ<27>
  191  VSS(26)  GROUND  = GND
  192  CB(5)  BI  = M_E_ECC<5>
  193  VSS(25)  GROUND  = GND
  194  CB(1)  BI  = M_E_ECC<1>
  195  VSS(24)  GROUND  = GND
  196  DQS8N  BI  = M_E_DQS_DN<8>
  197  DQS8P  BI  = M_E_DQS_DP<8>
  198  VSS(23)  GROUND  = GND
  199  CB(7)  BI  = M_E_ECC<7>
  200  VSS(22)  GROUND  = GND
  201  CB(3)  BI  = M_E_ECC<3>
  202  VSS(21)  GROUND  = GND
  203  CKE(1)  BI  = M_E_CKE<3>
  204  VDD(12)  POWER  = PVDDQ_DEF
  205  RFU(0)  BI  = TP_CH_E_DIMM_E1_RFU_0
  206  VDD(11)  POWER  = PVDDQ_DEF
  207  BG(1)  BI  = M_E_BG<1>
  208  ALERT_N  BI  = M_E_ALERT_N
  209  VDD(10)  POWER  = PVDDQ_DEF
  210  A11  BI  = M_E_MA<11>
  211  A7  BI  = M_E_MA<7>
  212  VDD(9)  POWER  = PVDDQ_DEF
  213  A5  BI  = M_E_MA<5>
  214  A4  BI  = M_E_MA<4>
  215  VDD(8)  POWER  = PVDDQ_DEF
  216  A2  BI  = M_E_MA<2>
  217  VDD(7)  POWER  = PVDDQ_DEF
  218  CK1P  BI  = M_E_CLK_DP<3>
  219  CK1N  BI  = M_E_CLK_DN<3>
  220  VDD(6)  POWER  = PVDDQ_DEF
  221  VTT(0)  POWER  = PVTT_DEF
  222  PAR  BI  = M_E_PAR
  223  VDD(5)  POWER  = PVDDQ_DEF
  224  BA(1)  BI  = M_E_BA<1>
  225  A10  BI  = M_E_MA<10>
  226  VDD(4)  POWER  = PVDDQ_DEF
  227  RFU(1)  BI  = TP_CH_E_DIMM_E1_RFU_1
  228  A14_WE_N  BI  = M_E_MA<14>
  229  VDD(3)  POWER  = PVDDQ_DEF
  230  SAVE_N_NC  BI  = FM_ADR_COMPLETE_DEF_N
  231  VDD(2)  POWER  = PVDDQ_DEF
  232  A13  BI  = M_E_MA<13>
  233  VDD(1)  POWER  = PVDDQ_DEF
  234  A17  BI  = M_E_MA<17>
  235  C(2)  BI  = M_E_C<2>
  236  VDD(0)  POWER  = PVDDQ_DEF
  237  S3_N_C(1)  BI  = M_E_CS_N<7>
  238  SA(2)  BI  = GND
  239  VSS(20)  GROUND  = GND
  240  DQ(37)  BI  = M_E_DQ<37>
  241  VSS(19)  GROUND  = GND
  242  DQ(33)  BI  = M_E_DQ<33>
  243  VSS(18)  GROUND  = GND
  244  DQS4N  BI  = M_E_DQS_DN<4>
  245  DQS4P  BI  = M_E_DQS_DP<4>
  246  VSS(17)  GROUND  = GND
  247  DQ(39)  BI  = M_E_DQ<39>
  248  VSS(16)  GROUND  = GND
  249  DQ(35)  BI  = M_E_DQ<35>
  250  VSS(15)  GROUND  = GND
  251  DQ(45)  BI  = M_E_DQ<45>
  252  VSS(14)  GROUND  = GND
  253  DQ(41)  BI  = M_E_DQ<41>
  254  VSS(13)  GROUND  = GND
  255  DQS5N  BI  = M_E_DQS_DN<5>
  256  DQS5P  BI  = M_E_DQS_DP<5>
  257  VSS(12)  GROUND  = GND
  258  DQ(47)  BI  = M_E_DQ<47>
  259  VSS(11)  GROUND  = GND
  260  DQ(43)  BI  = M_E_DQ<43>
  261  VSS(10)  GROUND  = GND
  262  DQ(53)  BI  = M_E_DQ<53>
  263  VSS(9)  GROUND  = GND
  264  DQ(49)  BI  = M_E_DQ<49>
  265  VSS(8)  GROUND  = GND
  266  DQS6N  BI  = M_E_DQS_DN<6>
  267  DQS6P  BI  = M_E_DQS_DP<6>
  268  VSS(7)  GROUND  = GND
  269  DQ(55)  BI  = M_E_DQ<55>
  270  VSS(6)  GROUND  = GND
  271  DQ(51)  BI  = M_E_DQ<51>
  272  VSS(5)  GROUND  = GND
  273  DQ(61)  BI  = M_E_DQ<61>
  274  VSS(4)  GROUND  = GND
  275  DQ(57)  BI  = M_E_DQ<57>
  276  VSS(3)  GROUND  = GND
  277  DQS7N  BI  = M_E_DQS_DN<7>
  278  DQS7P  BI  = M_E_DQS_DP<7>
  279  VSS(2)  GROUND  = GND
  280  DQ(63)  BI  = M_E_DQ<63>
  281  VSS(1)  GROUND  = GND
  282  DQ(59)  BI  = M_E_DQ<59>
  283  VSS(0)  GROUND  = GND
  284  VDDSPD  BI  = PVPP_DEF
  285  SDA  BI  = SMB_DDR_DEF_VPP_SDA
  286  VPP(1)  POWER  = PVPP_DEF
  287  VPP(0)  POWER  = PVPP_DEF
  288  VPP(2)  POWER  = PVPP_DEF
